# SCM (Grand Teton) — schematic netlist excerpt (pin names and nets, part order shuffled) for the footprints in the layout excerpt that follows; sources: Cadence DE-HDL packaged netlist, KiCad conversion of 12092022_DA0F0TMDCD0_F0T_Management_Board_D_brd_V3_OCP.brd

C211  Q_CAP  10PF 50V 1% NPO  pkg 0402  page 23 : A = V_VGAHS_BUF ; B = GND
R403  Q_RES  10K 1% CHIP  pkg 0402LF  page 53 : A = P3V3_AUX ; B = PWRGD_P2V5_AUX_R

(kicad_pcb
	(version 20260206)
	(generator "pcbnew")
	(generator_version "10.0")
	(general
		(thickness 1.6)
		(legacy_teardrops no)
	)
	(paper "A4")
	(title_block
		(title "12092022_DA0F0TMDCD0_F0T_Management_Board_D_brd_V3_OCP.brd")
		(comment 1 "Grand Teton / footprints 980-981 of 1440")
	)
	(layers
		(0 "F.Cu" signal "TOP")
		(4 "In1.Cu" signal "GND")
		(6 "In2.Cu" signal "IN1")
		(8 "In3.Cu" signal "GND1")
		(10 "In4.Cu" signal "IN2")
		(12 "In5.Cu" signal "VCC")
		(14 "In6.Cu" signal "VCC1")
		(16 "In7.Cu" signal "IN3")
		(18 "In8.Cu" signal "GND2")
		(20 "In9.Cu" signal "IN4")
		(22 "In10.Cu" signal "GND3")
		(2 "B.Cu" signal "BOTTOM")
		(9 "F.Adhes" user "F.Adhesive")
		(11 "B.Adhes" user "B.Adhesive")
		(13 "F.Paste" user "Package Geometry/Pastemask Top")
		(15 "B.Paste" user "Package Geometry/Pastemask Bottom")
		(5 "F.SilkS" user "Ref Des/Silkscreen Top")
		(7 "B.SilkS" user "Ref Des/Silkscreen Bottom")
		(1 "F.Mask" user "Board Geometry/Soldermask Top")
		(3 "B.Mask" user "Board Geometry/Soldermask Bottom")
		(17 "Dwgs.User" user "User.Drawings")
		(19 "Cmts.User" user "User.Comments")
		(21 "Eco1.User" user "User.Eco1")
		(23 "Eco2.User" user "User.Eco2")
		(25 "Edge.Cuts" user "Board Geometry/Outline")
		(27 "Margin" user)
		(31 "F.CrtYd" user "Package Geometry/Place Bound Top")
		(29 "B.CrtYd" user "Package Geometry/Place Bound Bottom")
		(35 "F.Fab" user "Ref Des/Assembly Top")
		(33 "B.Fab" user "Ref Des/Assembly Bottom")
	)
	(footprint ""
		(layer "B.Cu")
		(at 80.772 -33.4645 -90)
		(property "Reference" "R403"
			(at 0 0 90)
			(layer "B.SilkS")
			(hide yes)
			(effects
				(font
					(size 1.27 1.27)
				)
				(justify mirror)
			)
		)
		(property "Value" ""
			(at 0 0 90)
			(layer "B.Fab")
			(effects
				(font
					(size 1.27 1.27)
				)
				(justify mirror)
			)
		)
		(duplicate_pad_numbers_are_jumpers no)
		(fp_line
			(start -0.7874 0.4064)
			(end 0.7874 0.4064)
			(stroke
				(width 0.1524)
				(type default)
			)
			(layer "B.SilkS")
		)
		(fp_line
			(start 0.7874 0.4064)
			(end 0.7874 -0.4064)
			(stroke
				(width 0.1524)
				(type default)
			)
			(layer "B.SilkS")
		)
		(fp_line
			(start -0.7874 -0.4064)
			(end -0.7874 0.4064)
			(stroke
				(width 0.1524)
				(type default)
			)
			(layer "B.SilkS")
		)
		(fp_line
			(start 0.7874 -0.4064)
			(end -0.7874 -0.4064)
			(stroke
				(width 0.1524)
				(type default)
			)
			(layer "B.SilkS")
		)
		(fp_line
			(start -0.67945 0.3048)
			(end -0.120396 0.3048)
			(stroke
				(width 0.1)
				(type default)
			)
			(layer "B.Fab")
		)
		(fp_line
			(start -0.120396 0.3048)
			(end -0.120396 0.2794)
			(stroke
				(width 0.1)
				(type default)
			)
			(layer "B.Fab")
		)
		(fp_line
			(start 0.12065 0.3048)
			(end 0.67945 0.3048)
			(stroke
				(width 0.1)
				(type default)
			)
			(layer "B.Fab")
		)
		(fp_line
			(start 0.67945 0.3048)
			(end 0.67945 -0.305054)
			(stroke
				(width 0.1)
				(type default)
			)
			(layer "B.Fab")
		)
		(fp_line
			(start -0.120396 0.2794)
			(end 0.12065 0.2794)
			(stroke
				(width 0.1)
				(type default)
			)
			(layer "B.Fab")
		)
		(fp_line
			(start 0.12065 0.2794)
			(end 0.12065 0.3048)
			(stroke
				(width 0.1)
				(type default)
			)
			(layer "B.Fab")
		)
		(fp_line
			(start -0.12065 -0.2794)
			(end -0.12065 -0.3048)
			(stroke
				(width 0.1)
				(type default)
			)
			(layer "B.Fab")
		)
		(fp_line
			(start 0.12065 -0.2794)
			(end -0.12065 -0.2794)
			(stroke
				(width 0.1)
				(type default)
			)
			(layer "B.Fab")
		)
		(fp_line
			(start -0.67945 -0.3048)
			(end -0.67945 0.3048)
			(stroke
				(width 0.1)
				(type default)
			)
			(layer "B.Fab")
		)
		(fp_line
			(start -0.12065 -0.3048)
			(end -0.67945 -0.3048)
			(stroke
				(width 0.1)
				(type default)
			)
			(layer "B.Fab")
		)
		(fp_line
			(start 0.12065 -0.305054)
			(end 0.12065 -0.2794)
			(stroke
				(width 0.1)
				(type default)
			)
			(layer "B.Fab")
		)
		(fp_line
			(start 0.67945 -0.305054)
			(end 0.12065 -0.305054)
			(stroke
				(width 0.1)
				(type default)
			)
			(layer "B.Fab")
		)
		(pad "1" smd circle
			(at 0.40005 0 90)
			(size 0 0)
			(layers "B.Cu" "B.Mask" "B.Paste")
			(net "P3V3_AUX")
		)
		(pad "2" smd circle
			(at -0.40005 0 90)
			(size 0 0)
			(layers "B.Cu" "B.Mask" "B.Paste")
			(net "PWRGD_P2V5_AUX_R")
		)
	)
	(footprint ""
		(layer "B.Cu")
		(at 35.8902 -19.9898 180)
		(property "Reference" "C211"
			(at 0 0 0)
			(layer "B.SilkS")
			(hide yes)
			(effects
				(font
					(size 1.27 1.27)
				)
				(justify mirror)
			)
		)
		(property "Value" ""
			(at 0 0 0)
			(layer "B.Fab")
			(effects
				(font
					(size 1.27 1.27)
				)
				(justify mirror)
			)
		)
		(duplicate_pad_numbers_are_jumpers no)
		(fp_line
			(start 0.7874 0.4064)
			(end 0.7874 -0.4064)
			(stroke
				(width 0.1524)
				(type default)
			)
			(layer "B.SilkS")
		)
		(fp_line
			(start 0.7874 -0.4064)
			(end -0.7874 -0.4064)
			(stroke
				(width 0.1524)
				(type default)
			)
			(layer "B.SilkS")
		)
		(fp_line
			(start -0.7874 0.4064)
			(end 0.7874 0.4064)
			(stroke
				(width 0.1524)
				(type default)
			)
			(layer "B.SilkS")
		)
		(fp_line
			(start -0.7874 -0.4064)
			(end -0.7874 0.4064)
			(stroke
				(width 0.1524)
				(type default)
			)
			(layer "B.SilkS")
		)
		(fp_line
			(start 0.67945 0.3048)
			(end 0.67945 -0.305054)
			(stroke
				(width 0.1)
				(type default)
			)
			(layer "B.Fab")
		)
		(fp_line
			(start 0.67945 -0.305054)
			(end 0.12065 -0.305054)
			(stroke
				(width 0.1)
				(type default)
			)
			(layer "B.Fab")
		)
		(fp_line
			(start 0.12065 0.3048)
			(end 0.67945 0.3048)
			(stroke
				(width 0.1)
				(type default)
			)
			(layer "B.Fab")
		)
		(fp_line
			(start 0.12065 0.2794)
			(end 0.12065 0.3048)
			(stroke
				(width 0.1)
				(type default)
			)
			(layer "B.Fab")
		)
		(fp_line
			(start 0.12065 -0.2794)
			(end -0.12065 -0.2794)
			(stroke
				(width 0.1)
				(type default)
			)
			(layer "B.Fab")
		)
		(fp_line
			(start 0.12065 -0.305054)
			(end 0.12065 -0.2794)
			(stroke
				(width 0.1)
				(type default)
			)
			(layer "B.Fab")
		)
		(fp_line
			(start -0.120396 0.3048)
			(end -0.120396 0.2794)
			(stroke
				(width 0.1)
				(type default)
			)
			(layer "B.Fab")
		)
		(fp_line
			(start -0.120396 0.2794)
			(end 0.12065 0.2794)
			(stroke
				(width 0.1)
				(type default)
			)
			(layer "B.Fab")
		)
		(fp_line
			(start -0.12065 -0.2794)
			(end -0.12065 -0.3048)
			(stroke
				(width 0.1)
				(type default)
			)
			(layer "B.Fab")
		)
		(fp_line
			(start -0.12065 -0.3048)
			(end -0.67945 -0.3048)
			(stroke
				(width 0.1)
				(type default)
			)
			(layer "B.Fab")
		)
		(fp_line
			(start -0.67945 0.3048)
			(end -0.120396 0.3048)
			(stroke
				(width 0.1)
				(type default)
			)
			(layer "B.Fab")
		)
		(fp_line
			(start -0.67945 -0.3048)
			(end -0.67945 0.3048)
			(stroke
				(width 0.1)
				(type default)
			)
			(layer "B.Fab")
		)
		(pad "1" smd circle
			(at 0.40005 0)
			(size 0 0)
			(layers "B.Cu" "B.Mask" "B.Paste")
			(net "V_VGAHS_BUF")
		)
		(pad "2" smd circle
			(at -0.40005 0)
			(size 0 0)
			(layers "B.Cu" "B.Mask" "B.Paste")
			(net "GND")
		)
	)
)
